# BASEBOARD_FAB2 (Tioga Pass) — schematic netlist excerpt (pin names and nets, part order shuffled) for the footprints in the layout excerpt that follows; sources: Cadence DE-HDL packaged netlist, KiCad conversion of Wiwynn_Tioga_Pass_MB.brd

C22W13  SC22U16V5MX-4-GP  20%  pkg SMD-BCG5  page 214 : \1\ = VR_FET_SW_P12V_STBY_PVCCIN_CPU0 ; \2\ = GND
C4D24  CAP_A  0.1UF 16V 10% X7R  pkg 0402V  page 102 : A = P3V3_DB1200_A ; B = GND
C828  CAP  0.22UF 16V 10% X7R  pkg 0402  page 244 : A = P3E_CPU0_PE1_PCH_TXN<13> ; B = P3E_CPU0_PE1_PCH_CON_TXN<13>

(kicad_pcb
	(version 20260206)
	(generator "pcbnew")
	(generator_version "10.0")
	(general
		(thickness 1.6)
		(legacy_teardrops no)
	)
	(paper "A4")
	(title_block
		(title "Wiwynn_Tioga_Pass_MB.brd")
		(comment 1 "Tioga Pass / footprints 1328-1331 of 4770")
	)
	(layers
		(0 "F.Cu" signal "TOP")
		(4 "In1.Cu" signal "L2GND")
		(6 "In2.Cu" signal "L3")
		(8 "In3.Cu" signal "L4GND")
		(10 "In4.Cu" signal "L5")
		(12 "In5.Cu" signal "L6GND")
		(14 "In6.Cu" signal "L7VCC")
		(16 "In7.Cu" signal "L8VCC")
		(18 "In8.Cu" signal "L9GND")
		(20 "In9.Cu" signal "L10")
		(22 "In10.Cu" signal "L11GND")
		(24 "In11.Cu" signal "L12")
		(26 "In12.Cu" signal "L13GND")
		(2 "B.Cu" signal "BOTTOM")
		(9 "F.Adhes" user "F.Adhesive")
		(11 "B.Adhes" user "B.Adhesive")
		(13 "F.Paste" user "Package Geometry/Pastemask Top")
		(15 "B.Paste" user "Package Geometry/Pastemask Bottom")
		(5 "F.SilkS" user "Ref Des/Silkscreen Top")
		(7 "B.SilkS" user "Ref Des/Silkscreen Bottom")
		(1 "F.Mask" user "Board Geometry/Soldermask Top")
		(3 "B.Mask" user "Board Geometry/Soldermask Bottom")
		(17 "Dwgs.User" user "User.Drawings")
		(19 "Cmts.User" user "User.Comments")
		(21 "Eco1.User" user "User.Eco1")
		(23 "Eco2.User" user "User.Eco2")
		(25 "Edge.Cuts" user "Board Geometry/Outline")
		(27 "Margin" user)
		(31 "F.CrtYd" user "Package Geometry/Place Bound Top")
		(29 "B.CrtYd" user "Package Geometry/Place Bound Bottom")
		(35 "F.Fab" user "Ref Des/Assembly Top")
		(33 "B.Fab" user "Ref Des/Assembly Bottom")
	)
	(footprint ""
		(layer "F.Cu")
		(at 165.354 -74.803)
		(property "Reference" "C4D24"
			(at 0 0 0)
			(layer "F.SilkS")
			(hide yes)
			(effects
				(font
					(size 1.27 1.27)
				)
			)
		)
		(property "Value" ""
			(at 0 0 0)
			(layer "F.Fab")
			(effects
				(font
					(size 1.27 1.27)
				)
			)
		)
		(duplicate_pad_numbers_are_jumpers no)
		(fp_poly
			(pts
				(xy 0.3048 -0.1016) (xy 0.3048 0.9906) (xy -0.3048 0.9906) (xy -0.3048 -0.1016)
			)
			(stroke
				(width 0)
				(type default)
			)
			(fill no)
			(layer "F.CrtYd")
		)
		(fp_line
			(start -0.3048 -0.1016)
			(end -0.3048 0.9906)
			(stroke
				(width 0.1)
				(type default)
			)
			(layer "F.Fab")
		)
		(fp_line
			(start -0.3048 0.9906)
			(end 0.3048 0.9906)
			(stroke
				(width 0.1)
				(type default)
			)
			(layer "F.Fab")
		)
		(fp_line
			(start 0.3048 -0.1016)
			(end -0.3048 -0.1016)
			(stroke
				(width 0.1)
				(type default)
			)
			(layer "F.Fab")
		)
		(fp_line
			(start 0.3048 0.9906)
			(end 0.3048 -0.1016)
			(stroke
				(width 0.1)
				(type default)
			)
			(layer "F.Fab")
		)
		(pad "1" smd rect
			(at 0 0)
			(size 0.508 0.508)
			(layers "F.Cu" "F.Mask" "F.Paste")
			(net "P3V3_DB1200_A")
		)
		(pad "2" smd rect
			(at 0 0.889)
			(size 0.508 0.508)
			(layers "F.Cu" "F.Mask" "F.Paste")
			(net "GND")
		)
		(zone
			(layer "F.Cu")
			(hatch none 0.5)
			(connect_pads
				(clearance 0)
			)
			(min_thickness 0.25)
			(keepout
				(tracks allowed)
				(vias not_allowed)
				(pads allowed)
				(copperpour not_allowed)
				(footprints allowed)
			)
			(placement
				(enabled no)
				(sheetname "")
			)
			(fill
				(thermal_gap 0.5)
				(thermal_bridge_width 0.5)
				(island_removal_mode 0)
			)
			(polygon
				(pts
					(xy 165.1 -74.549) (xy 165.608 -74.549) (xy 165.608 -74.168) (xy 165.1 -74.168)
				)
			)
		)
		(zone
			(layer "F.Cu")
			(hatch none 0.5)
			(connect_pads
				(clearance 0)
			)
			(min_thickness 0.25)
			(keepout
				(tracks not_allowed)
				(vias allowed)
				(pads allowed)
				(copperpour not_allowed)
				(footprints allowed)
			)
			(placement
				(enabled no)
				(sheetname "")
			)
			(fill
				(thermal_gap 0.5)
				(thermal_bridge_width 0.5)
				(island_removal_mode 0)
			)
			(polygon
				(pts
					(xy 165.1 -74.168) (xy 165.608 -74.168) (xy 165.608 -74.549) (xy 165.1 -74.549)
				)
			)
		)
	)
	(footprint ""
		(layer "F.Cu")
		(at 42.31513 -109.512862)
		(property "Reference" ""
			(at 0 0 0)
			(layer "F.SilkS")
			(hide yes)
			(effects
				(font
					(size 1.27 1.27)
				)
			)
		)
		(property "Value" ""
			(at 0 0 0)
			(layer "F.Fab")
			(effects
				(font
					(size 1.27 1.27)
				)
			)
		)
		(duplicate_pad_numbers_are_jumpers no)
		(fp_poly
			(pts
				(arc
					(start 2.032 0)
					(mid -2.032 0)
					(end 2.032 0)
				)
			)
			(stroke
				(width 0)
				(type default)
			)
			(fill no)
			(layer "F.CrtYd")
		)
		(pad "1" smd circle
			(at 0 0)
			(size 1.016 1.016)
			(layers "F.Cu" "F.Mask" "F.Paste")
			(net "Net_385")
		)
		(zone
			(layer "F.Cu")
			(hatch none 0.5)
			(connect_pads
				(clearance 0)
			)
			(min_thickness 0.25)
			(keepout
				(tracks not_allowed)
				(vias allowed)
				(pads allowed)
				(copperpour not_allowed)
				(footprints allowed)
			)
			(placement
				(enabled no)
				(sheetname "")
			)
			(fill
				(thermal_gap 0.5)
				(thermal_bridge_width 0.5)
				(island_removal_mode 0)
			)
			(polygon
				(pts
					(arc
						(start 43.83913 -109.512862)
						(mid 40.79113 -109.512862)
						(end 43.83913 -109.512862)
					)
				)
			)
		)
		(zone
			(layers "F.Cu" "B.Cu" "In1.Cu" "In2.Cu" "In3.Cu" "In4.Cu" "In5.Cu" "In6.Cu"
				"In7.Cu" "In8.Cu" "In9.Cu" "In10.Cu" "In11.Cu" "In12.Cu"
			)
			(hatch none 0.5)
			(connect_pads
				(clearance 0)
			)
			(min_thickness 0.25)
			(keepout
				(tracks allowed)
				(vias not_allowed)
				(pads allowed)
				(copperpour not_allowed)
				(footprints allowed)
			)
			(placement
				(enabled no)
				(sheetname "")
			)
			(fill
				(thermal_gap 0.5)
				(thermal_bridge_width 0.5)
				(island_removal_mode 0)
			)
			(polygon
				(pts
					(arc
						(start 43.83913 -109.512862)
						(mid 40.79113 -109.512862)
						(end 43.83913 -109.512862)
					)
				)
			)
		)
	)
	(footprint ""
		(layer "F.Cu")
		(at 186.015376 -59.243722 180)
		(property "Reference" "C22W13"
			(at 0 0 180)
			(layer "F.SilkS")
			(hide yes)
			(effects
				(font
					(size 1.27 1.27)
				)
			)
		)
		(property "Value" "*"
			(at -0.0762 -6.2357 180)
			(unlocked yes)
			(layer "F.Fab")
			(hide yes)
			(effects
				(font
					(size 1.27 1.016)
					(thickness 0.1524)
				)
			)
		)
		(property "Device Type" "SC22U16V5MX-4-GP_SMD-BCG5-SC22A"
			(at -0.0762 -8.2677 180)
			(unlocked yes)
			(layer "F.Fab")
			(hide yes)
			(effects
				(font
					(size 1.27 1.016)
					(thickness 0.1524)
				)
			)
		)
		(duplicate_pad_numbers_are_jumpers no)
		(fp_line
			(start 0.635 0)
			(end -0.635 0)
			(stroke
				(width 0.508)
				(type default)
			)
			(layer "F.SilkS")
		)
		(fp_rect
			(start -0.9652 1.778)
			(end 0.9652 -1.778)
			(stroke
				(width 0)
				(type default)
			)
			(fill no)
			(layer "F.CrtYd")
		)
		(fp_poly
			(pts
				(xy -0.9652 -1.778) (xy 0.9652 -1.778) (xy 0.9652 1.778) (xy -0.9652 1.778)
			)
			(stroke
				(width 0)
				(type default)
			)
			(fill no)
			(layer "F.Fab")
		)
		(pad "1" smd rect
			(at 0 -0.9652 180)
			(size 1.397 1.143)
			(layers "F.Cu" "F.Mask" "F.Paste")
			(net "VR_FET_SW_P12V_STBY_PVCCIN_CPU0")
		)
		(pad "2" smd rect
			(at 0 0.9652 180)
			(size 1.397 1.143)
			(layers "F.Cu" "F.Mask" "F.Paste")
			(net "GND")
		)
	)
	(footprint ""
		(layer "F.Cu")
		(at 324.5485 -121.666 -90)
		(property "Reference" "C828"
			(at -0.8382 -0.67818 270)
			(unlocked yes)
			(layer "F.SilkS")
			(effects
				(font
					(size 0.4064 0.254)
					(thickness 0.1524)
				)
				(justify left)
			)
		)
		(property "Value" ""
			(at 0 0 270)
			(layer "F.Fab")
			(effects
				(font
					(size 1.27 1.27)
				)
			)
		)
		(duplicate_pad_numbers_are_jumpers no)
		(fp_poly
			(pts
				(xy 0.3048 -0.1016) (xy 0.3048 0.9906) (xy -0.3048 0.9906) (xy -0.3048 -0.1016)
			)
			(stroke
				(width 0)
				(type default)
			)
			(fill no)
			(layer "F.CrtYd")
		)
		(fp_line
			(start -0.3048 0.9906)
			(end 0.3048 0.9906)
			(stroke
				(width 0.1)
				(type default)
			)
			(layer "F.Fab")
		)
		(fp_line
			(start 0.3048 0.9906)
			(end 0.3048 -0.1016)
			(stroke
				(width 0.1)
				(type default)
			)
			(layer "F.Fab")
		)
		(fp_line
			(start -0.3048 -0.1016)
			(end -0.3048 0.9906)
			(stroke
				(width 0.1)
				(type default)
			)
			(layer "F.Fab")
		)
		(fp_line
			(start 0.3048 -0.1016)
			(end -0.3048 -0.1016)
			(stroke
				(width 0.1)
				(type default)
			)
			(layer "F.Fab")
		)
		(pad "1" smd rect
			(at 0 0 270)
			(size 0.508 0.508)
			(layers "F.Cu" "F.Mask" "F.Paste")
			(net "P3E_CPU0_PE1_PCH_TXN<13>")
		)
		(pad "2" smd rect
			(at 0 0.889 270)
			(size 0.508 0.508)
			(layers "F.Cu" "F.Mask" "F.Paste")
			(net "P3E_CPU0_PE1_PCH_CON_TXN<13>")
		)
		(zone
			(layer "F.Cu")
			(hatch none 0.5)
			(connect_pads
				(clearance 0)
			)
			(min_thickness 0.25)
			(keepout
				(tracks allowed)
				(vias not_allowed)
				(pads allowed)
				(copperpour not_allowed)
				(footprints allowed)
			)
			(placement
				(enabled no)
				(sheetname "")
			)
			(fill
				(thermal_gap 0.5)
				(thermal_bridge_width 0.5)
				(island_removal_mode 0)
			)
			(polygon
				(pts
					(xy 324.2945 -121.92) (xy 324.2945 -121.412) (xy 323.9135 -121.412) (xy 323.9135 -121.92)
				)
			)
		)
	)
)
